# T6G (Grand Teton) — schematic netlist excerpt (pin names and nets, part order shuffled) for the footprints in the layout excerpt that follows; sources: Cadence DE-HDL packaged netlist, KiCad conversion of 04192023_DAF0TMB3IC0_F0TG_MB_C_brd_V02_OCP.brd

R3274  Q_RES  68K 1% EMPTY  pkg 0402LF  page 111 : A = FM_P2E_EQA0 ; B = GND
C6027  Q_CAP  22UF 16V 20% X6S  pkg C0805  page 176 : A = P5V_AUX ; B = GND

U8001  APX80929SAG7  APX809-29SAG-7 IC  pkg SOT23_123XI  page 136
  GND  = GND
  RESET_L  = OCP_V3_1_P3V3_R1_PWRGD
  VCC  = P3V3_OCP_SFF_R

(kicad_pcb
	(version 20260206)
	(generator "pcbnew")
	(generator_version "10.0")
	(general
		(thickness 1.6)
		(legacy_teardrops no)
	)
	(paper "A4")
	(title_block
		(title "04192023_DAF0TMB3IC0_F0TG_MB_C_brd_V02_OCP.brd")
		(comment 1 "Grand Teton / footprints 2673-2675 of 8354")
	)
	(layers
		(0 "F.Cu" signal "TOP")
		(4 "In1.Cu" signal "GND")
		(6 "In2.Cu" signal "IN1")
		(8 "In3.Cu" signal "GND1")
		(10 "In4.Cu" signal "IN2")
		(12 "In5.Cu" signal "GND2")
		(14 "In6.Cu" signal "IN3")
		(16 "In7.Cu" signal "GND3")
		(18 "In8.Cu" signal "VCC")
		(20 "In9.Cu" signal "VCC1")
		(22 "In10.Cu" signal "GND4")
		(24 "In11.Cu" signal "IN4")
		(26 "In12.Cu" signal "GND5")
		(28 "In13.Cu" signal "IN5")
		(30 "In14.Cu" signal "GND6")
		(32 "In15.Cu" signal "IN6")
		(34 "In16.Cu" signal "GND7")
		(2 "B.Cu" signal "BOTTOM")
		(9 "F.Adhes" user "F.Adhesive")
		(11 "B.Adhes" user "B.Adhesive")
		(13 "F.Paste" user "Package Geometry/Pastemask Top")
		(15 "B.Paste" user "Package Geometry/Pastemask Bottom")
		(5 "F.SilkS" user "Ref Des/Silkscreen Top")
		(7 "B.SilkS" user "Ref Des/Silkscreen Bottom")
		(1 "F.Mask" user "Board Geometry/Soldermask Top")
		(3 "B.Mask" user "Board Geometry/Soldermask Bottom")
		(17 "Dwgs.User" user "User.Drawings")
		(19 "Cmts.User" user "User.Comments")
		(21 "Eco1.User" user "User.Eco1")
		(23 "Eco2.User" user "User.Eco2")
		(25 "Edge.Cuts" user "Board Geometry/Outline")
		(27 "Margin" user)
		(31 "F.CrtYd" user "Package Geometry/Place Bound Top")
		(29 "B.CrtYd" user "Package Geometry/Place Bound Bottom")
		(35 "F.Fab" user "Ref Des/Assembly Top")
		(33 "B.Fab" user "Ref Des/Assembly Bottom")
	)
	(footprint ""
		(layer "F.Cu")
		(at 26.793444 -424.525694 180)
		(property "Reference" "R3274"
			(at 0 0 180)
			(layer "F.SilkS")
			(hide yes)
			(effects
				(font
					(size 1.27 1.27)
				)
			)
		)
		(property "Value" ""
			(at 0 0 180)
			(layer "F.Fab")
			(effects
				(font
					(size 1.27 1.27)
				)
			)
		)
		(duplicate_pad_numbers_are_jumpers no)
		(fp_line
			(start 0.7874 0.4064)
			(end -0.7874 0.4064)
			(stroke
				(width 0.1524)
				(type default)
			)
			(layer "F.SilkS")
		)
		(fp_line
			(start 0.7874 -0.4064)
			(end 0.7874 0.4064)
			(stroke
				(width 0.1524)
				(type default)
			)
			(layer "F.SilkS")
		)
		(fp_line
			(start -0.7874 0.4064)
			(end -0.7874 -0.4064)
			(stroke
				(width 0.1524)
				(type default)
			)
			(layer "F.SilkS")
		)
		(fp_line
			(start -0.7874 -0.4064)
			(end 0.7874 -0.4064)
			(stroke
				(width 0.1524)
				(type default)
			)
			(layer "F.SilkS")
		)
		(fp_line
			(start 0.67945 0.3048)
			(end 0.120396 0.3048)
			(stroke
				(width 0.1)
				(type default)
			)
			(layer "F.Fab")
		)
		(fp_line
			(start 0.67945 -0.3048)
			(end 0.67945 0.3048)
			(stroke
				(width 0.1)
				(type default)
			)
			(layer "F.Fab")
		)
		(fp_line
			(start 0.12065 -0.2794)
			(end 0.12065 -0.3048)
			(stroke
				(width 0.1)
				(type default)
			)
			(layer "F.Fab")
		)
		(fp_line
			(start 0.12065 -0.3048)
			(end 0.67945 -0.3048)
			(stroke
				(width 0.1)
				(type default)
			)
			(layer "F.Fab")
		)
		(fp_line
			(start 0.120396 0.3048)
			(end 0.120396 0.2794)
			(stroke
				(width 0.1)
				(type default)
			)
			(layer "F.Fab")
		)
		(fp_line
			(start 0.120396 0.2794)
			(end -0.12065 0.2794)
			(stroke
				(width 0.1)
				(type default)
			)
			(layer "F.Fab")
		)
		(fp_line
			(start -0.12065 0.3048)
			(end -0.67945 0.3048)
			(stroke
				(width 0.1)
				(type default)
			)
			(layer "F.Fab")
		)
		(fp_line
			(start -0.12065 0.2794)
			(end -0.12065 0.3048)
			(stroke
				(width 0.1)
				(type default)
			)
			(layer "F.Fab")
		)
		(fp_line
			(start -0.12065 -0.2794)
			(end 0.12065 -0.2794)
			(stroke
				(width 0.1)
				(type default)
			)
			(layer "F.Fab")
		)
		(fp_line
			(start -0.12065 -0.305054)
			(end -0.12065 -0.2794)
			(stroke
				(width 0.1)
				(type default)
			)
			(layer "F.Fab")
		)
		(fp_line
			(start -0.67945 0.3048)
			(end -0.67945 -0.305054)
			(stroke
				(width 0.1)
				(type default)
			)
			(layer "F.Fab")
		)
		(fp_line
			(start -0.67945 -0.305054)
			(end -0.12065 -0.305054)
			(stroke
				(width 0.1)
				(type default)
			)
			(layer "F.Fab")
		)
		(pad "1" smd circle
			(at -0.40005 0 180)
			(size 0 0)
			(layers "F.Cu" "F.Mask" "F.Paste")
			(net "FM_P2E_EQA0")
		)
		(pad "2" smd circle
			(at 0.40005 0 180)
			(size 0 0)
			(layers "F.Cu" "F.Mask" "F.Paste")
			(net "GND")
		)
	)
	(footprint ""
		(layer "F.Cu")
		(at 141.624812 -50.556414)
		(property "Reference" "C6027"
			(at 0 0 0)
			(layer "F.SilkS")
			(hide yes)
			(effects
				(font
					(size 1.27 1.27)
				)
			)
		)
		(property "Value" ""
			(at 0 0 0)
			(layer "F.Fab")
			(effects
				(font
					(size 1.27 1.27)
				)
			)
		)
		(duplicate_pad_numbers_are_jumpers no)
		(fp_line
			(start -1.524 -0.762)
			(end 1.524 -0.762)
			(stroke
				(width 0.1524)
				(type default)
			)
			(layer "F.SilkS")
		)
		(fp_line
			(start -1.524 0.762)
			(end -1.524 -0.762)
			(stroke
				(width 0.1524)
				(type default)
			)
			(layer "F.SilkS")
		)
		(fp_line
			(start 1.524 -0.762)
			(end 1.524 0.762)
			(stroke
				(width 0.1524)
				(type default)
			)
			(layer "F.SilkS")
		)
		(fp_line
			(start 1.524 0.762)
			(end -1.524 0.762)
			(stroke
				(width 0.1524)
				(type default)
			)
			(layer "F.SilkS")
		)
		(fp_line
			(start -1.1049 -0.724916)
			(end -1.1049 0.724916)
			(stroke
				(width 0.1)
				(type default)
			)
			(layer "F.Fab")
		)
		(fp_line
			(start -1.1049 0.724916)
			(end 1.1049 0.724916)
			(stroke
				(width 0.1)
				(type default)
			)
			(layer "F.Fab")
		)
		(fp_line
			(start 1.1049 -0.724916)
			(end -1.1049 -0.724916)
			(stroke
				(width 0.1)
				(type default)
			)
			(layer "F.Fab")
		)
		(fp_line
			(start 1.1049 0.724916)
			(end 1.1049 -0.724916)
			(stroke
				(width 0.1)
				(type default)
			)
			(layer "F.Fab")
		)
		(pad "1" smd rect
			(at -0.889 0 180)
			(size 1.016 1.27)
			(layers "F.Cu" "F.Mask" "F.Paste")
			(net "P5V_AUX")
		)
		(pad "2" smd rect
			(at 0.889 0 180)
			(size 1.016 1.27)
			(layers "F.Cu" "F.Mask" "F.Paste")
			(net "GND")
		)
	)
	(footprint ""
		(layer "F.Cu")
		(at 416.179 -99.441 -90)
		(property "Reference" "U8001"
			(at -3.030474 1.59004 0)
			(unlocked yes)
			(layer "F.SilkS")
			(effects
				(font
					(size 0.7874 0.5842)
					(thickness 0.1524)
				)
				(justify left)
			)
		)
		(property "Value" ""
			(at 0 0 270)
			(layer "F.Fab")
			(effects
				(font
					(size 1.27 1.27)
				)
			)
		)
		(duplicate_pad_numbers_are_jumpers no)
		(fp_line
			(start -1.759712 1.500124)
			(end -1.759712 -1.500124)
			(stroke
				(width 0.1524)
				(type default)
			)
			(layer "F.SilkS")
		)
		(fp_line
			(start 1.759712 1.500124)
			(end -1.759712 1.500124)
			(stroke
				(width 0.1524)
				(type default)
			)
			(layer "F.SilkS")
		)
		(fp_line
			(start -1.759712 -1.500124)
			(end 1.759712 -1.500124)
			(stroke
				(width 0.1524)
				(type default)
			)
			(layer "F.SilkS")
		)
		(fp_line
			(start 1.759712 -1.500124)
			(end 1.759712 1.500124)
			(stroke
				(width 0.1524)
				(type default)
			)
			(layer "F.SilkS")
		)
		(fp_line
			(start -0.700024 1.500124)
			(end -0.700024 -1.500124)
			(stroke
				(width 0.1)
				(type default)
			)
			(layer "F.Fab")
		)
		(fp_line
			(start 0.700024 1.500124)
			(end -0.700024 1.500124)
			(stroke
				(width 0.1)
				(type default)
			)
			(layer "F.Fab")
		)
		(fp_line
			(start -0.700024 -1.500124)
			(end 0.700024 -1.500124)
			(stroke
				(width 0.1)
				(type default)
			)
			(layer "F.Fab")
		)
		(fp_line
			(start 0.700024 -1.500124)
			(end 0.700024 1.500124)
			(stroke
				(width 0.1)
				(type default)
			)
			(layer "F.Fab")
		)
		(pad "1" smd rect
			(at -1.150112 -0.94996 180)
			(size 0.6604 0.9652)
			(layers "F.Cu" "F.Mask" "F.Paste")
			(net "GND")
		)
		(pad "2" smd rect
			(at -1.150112 0.94996 180)
			(size 0.6604 0.9652)
			(layers "F.Cu" "F.Mask" "F.Paste")
			(net "OCP_V3_1_P3V3_R1_PWRGD")
		)
		(pad "3" smd rect
			(at 1.150112 0 180)
			(size 0.6604 0.9652)
			(layers "F.Cu" "F.Mask" "F.Paste")
			(net "P3V3_OCP_SFF_R")
		)
	)
)
